(kicad_pcb
	(version 20260206)
	(generator "pcbnew")
	(generator_version "10.0")
	(general
		(thickness 1.6)
		(legacy_teardrops no)
	)
	(paper "A4")
	(title_block
		(title "peb — Lightning_PEB_BRD.brd")
		(comment 1 "Lightning (Wiwynn / Facebook NVMe JBOF) / footprints 517-522 of 2563")
	)
	(layers
		(0 "F.Cu" signal "TOP")
		(4 "In1.Cu" signal "L2GND")
		(6 "In2.Cu" signal "L3")
		(8 "In3.Cu" signal "L4VCC")
		(10 "In4.Cu" signal "L5VCC")
		(12 "In5.Cu" signal "L6")
		(14 "In6.Cu" signal "L7GND")
		(2 "B.Cu" signal "BOTTOM")
		(9 "F.Adhes" user "F.Adhesive")
		(11 "B.Adhes" user "B.Adhesive")
		(13 "F.Paste" user "Package Geometry/Pastemask Top")
		(15 "B.Paste" user "Package Geometry/Pastemask Bottom")
		(5 "F.SilkS" user "Ref Des/Silkscreen Top")
		(7 "B.SilkS" user "Ref Des/Silkscreen Bottom")
		(1 "F.Mask" user "Board Geometry/Soldermask Top")
		(3 "B.Mask" user "Board Geometry/Soldermask Bottom")
		(17 "Dwgs.User" user "User.Drawings")
		(19 "Cmts.User" user "User.Comments")
		(21 "Eco1.User" user "User.Eco1")
		(23 "Eco2.User" user "User.Eco2")
		(25 "Edge.Cuts" user "Board Geometry/Outline")
		(27 "Margin" user)
		(31 "F.CrtYd" user "Package Geometry/Place Bound Top")
		(29 "B.CrtYd" user "Package Geometry/Place Bound Bottom")
		(35 "F.Fab" user "Ref Des/Assembly Top")
		(33 "B.Fab" user "Ref Des/Assembly Bottom")
	)
	(footprint ""
		(layer "F.Cu")
		(at 330.6572 -207.8736 -90)
		(property "Reference" "C4156"
			(at 0 0 270)
			(layer "F.SilkS")
			(hide yes)
			(effects
				(font
					(size 1.27 1.27)
				)
			)
		)
		(property "Value" "SCD1U25V3KX-GP"
			(at 0 -2.8194 270)
			(unlocked yes)
			(layer "F.Fab")
			(hide yes)
			(effects
				(font
					(size 1.016 1.016)
					(thickness 0.1524)
				)
			)
		)
		(property "Device Type" "C603H36"
			(at 0 -4.3434 270)
			(unlocked yes)
			(layer "F.Fab")
			(hide yes)
			(effects
				(font
					(size 1.016 1.016)
					(thickness 0.1524)
				)
			)
		)
		(duplicate_pad_numbers_are_jumpers no)
		(fp_line
			(start 0.508 0)
			(end -0.508 0)
			(stroke
				(width 0.2032)
				(type default)
			)
			(layer "F.SilkS")
		)
		(fp_rect
			(start -0.5842 1.3335)
			(end 0.5842 -1.3335)
			(stroke
				(width 0)
				(type default)
			)
			(fill no)
			(layer "F.CrtYd")
		)
		(fp_rect
			(start -0.5842 1.3335)
			(end 0.5842 -1.3335)
			(stroke
				(width 0)
				(type default)
			)
			(fill no)
			(layer "F.Fab")
		)
		(pad "1" smd custom
			(at 0 -0.762 270)
			(size 0.2159 0.2159)
			(layers "F.Cu" "F.Mask" "F.Paste")
			(net "GND")
			(options
				(clearance outline)
				(anchor circle)
			)
			(primitives
				(gr_poly
					(pts
						(arc
							(start -0.3302 -0.4318)
							(mid -0.402042 -0.402042)
							(end -0.4318 -0.3302)
						)
						(arc
							(start -0.4318 0.3302)
							(mid -0.402042 0.402042)
							(end -0.3302 0.4318)
						)
						(arc
							(start 0.3302 0.4318)
							(mid 0.402042 0.402042)
							(end 0.4318 0.3302)
						)
						(arc
							(start 0.4318 -0.3302)
							(mid 0.402042 -0.402042)
							(end 0.3302 -0.4318)
						)
					)
					(width 0)
					(fill yes)
				)
			)
		)
		(pad "2" smd custom
			(at 0 0.762 270)
			(size 0.2159 0.2159)
			(layers "F.Cu" "F.Mask" "F.Paste")
			(net "SSD_PWREN9_R")
			(options
				(clearance outline)
				(anchor circle)
			)
			(primitives
				(gr_poly
					(pts
						(arc
							(start -0.3302 -0.4318)
							(mid -0.402042 -0.402042)
							(end -0.4318 -0.3302)
						)
						(arc
							(start -0.4318 0.3302)
							(mid -0.402042 0.402042)
							(end -0.3302 0.4318)
						)
						(arc
							(start 0.3302 0.4318)
							(mid 0.402042 0.402042)
							(end 0.4318 0.3302)
						)
						(arc
							(start 0.4318 -0.3302)
							(mid 0.402042 -0.402042)
							(end 0.3302 -0.4318)
						)
					)
					(width 0)
					(fill yes)
				)
			)
		)
	)
	(footprint ""
		(layer "F.Cu")
		(at 122.0978 -91.7702 180)
		(property "Reference" "R861"
			(at 0 0 180)
			(layer "F.SilkS")
			(hide yes)
			(effects
				(font
					(size 1.27 1.27)
				)
			)
		)
		(property "Value" "0R2J-2-GP"
			(at 0.064008 -3.993896 180)
			(unlocked yes)
			(layer "F.Fab")
			(hide yes)
			(effects
				(font
					(size 1.016 1.016)
					(thickness 0.1524)
				)
			)
		)
		(property "Device Type" "R402H16"
			(at 0.064008 -5.517896 180)
			(unlocked yes)
			(layer "F.Fab")
			(hide yes)
			(effects
				(font
					(size 1.016 1.016)
					(thickness 0.1524)
				)
			)
		)
		(duplicate_pad_numbers_are_jumpers no)
		(fp_line
			(start 0.508 -0.9398)
			(end -0.508 -0.9398)
			(stroke
				(width 0.1524)
				(type default)
			)
			(layer "F.SilkS")
		)
		(fp_line
			(start -0.508 -0.9398)
			(end -0.508 0.9398)
			(stroke
				(width 0.1524)
				(type default)
			)
			(layer "F.SilkS")
		)
		(fp_rect
			(start -0.508 0.9398)
			(end 0.508 -0.9398)
			(stroke
				(width 0)
				(type default)
			)
			(fill no)
			(layer "F.CrtYd")
		)
		(fp_rect
			(start -0.508 0.9398)
			(end 0.508 -0.9398)
			(stroke
				(width 0)
				(type default)
			)
			(fill no)
			(layer "F.Fab")
		)
		(pad "1" smd custom
			(at 0 -0.4445 180)
			(size 0.1397 0.1397)
			(layers "F.Cu" "F.Mask" "F.Paste")
			(net "BMC_I2C10_8536_SCL")
			(options
				(clearance outline)
				(anchor circle)
			)
			(primitives
				(gr_poly
					(pts
						(arc
							(start -0.1778 -0.2794)
							(mid -0.249642 -0.249642)
							(end -0.2794 -0.1778)
						)
						(arc
							(start -0.2794 0.1778)
							(mid -0.249642 0.249642)
							(end -0.1778 0.2794)
						)
						(arc
							(start 0.1778 0.2794)
							(mid 0.249642 0.249642)
							(end 0.2794 0.1778)
						)
						(arc
							(start 0.2794 -0.1778)
							(mid 0.249642 -0.249642)
							(end 0.1778 -0.2794)
						)
					)
					(width 0)
					(fill yes)
				)
			)
		)
		(pad "2" smd custom
			(at 0 0.4445 180)
			(size 0.1397 0.1397)
			(layers "F.Cu" "F.Mask" "F.Paste")
			(net "BMC_I2C10_8536_SCL_R")
			(options
				(clearance outline)
				(anchor circle)
			)
			(primitives
				(gr_poly
					(pts
						(arc
							(start -0.1778 -0.2794)
							(mid -0.249642 -0.249642)
							(end -0.2794 -0.1778)
						)
						(arc
							(start -0.2794 0.1778)
							(mid -0.249642 0.249642)
							(end -0.1778 0.2794)
						)
						(arc
							(start 0.1778 0.2794)
							(mid 0.249642 0.249642)
							(end 0.2794 0.1778)
						)
						(arc
							(start 0.2794 -0.1778)
							(mid 0.249642 -0.249642)
							(end 0.1778 -0.2794)
						)
					)
					(width 0)
					(fill yes)
				)
			)
		)
	)
	(footprint ""
		(layer "F.Cu")
		(at 6.858 -91.694 180)
		(property "Reference" "R528"
			(at 0 0 180)
			(layer "F.SilkS")
			(hide yes)
			(effects
				(font
					(size 1.27 1.27)
				)
			)
		)
		(property "Value" "33R2J-2-GP"
			(at 0.064008 -3.993896 180)
			(unlocked yes)
			(layer "F.Fab")
			(hide yes)
			(effects
				(font
					(size 1.016 1.016)
					(thickness 0.1524)
				)
			)
		)
		(property "Device Type" "R402H16"
			(at 0.064008 -5.517896 180)
			(unlocked yes)
			(layer "F.Fab")
			(hide yes)
			(effects
				(font
					(size 1.016 1.016)
					(thickness 0.1524)
				)
			)
		)
		(duplicate_pad_numbers_are_jumpers no)
		(fp_line
			(start 0.508 -0.9398)
			(end -0.508 -0.9398)
			(stroke
				(width 0.1524)
				(type default)
			)
			(layer "F.SilkS")
		)
		(fp_line
			(start -0.508 -0.9398)
			(end -0.508 0.9398)
			(stroke
				(width 0.1524)
				(type default)
			)
			(layer "F.SilkS")
		)
		(fp_rect
			(start -0.508 0.9398)
			(end 0.508 -0.9398)
			(stroke
				(width 0)
				(type default)
			)
			(fill no)
			(layer "F.CrtYd")
		)
		(fp_rect
			(start -0.508 0.9398)
			(end 0.508 -0.9398)
			(stroke
				(width 0)
				(type default)
			)
			(fill no)
			(layer "F.Fab")
		)
		(pad "1" smd custom
			(at 0 -0.4445 180)
			(size 0.1397 0.1397)
			(layers "F.Cu" "F.Mask" "F.Paste")
			(net "50M_CLK_OUT")
			(options
				(clearance outline)
				(anchor circle)
			)
			(primitives
				(gr_poly
					(pts
						(arc
							(start -0.1778 -0.2794)
							(mid -0.249642 -0.249642)
							(end -0.2794 -0.1778)
						)
						(arc
							(start -0.2794 0.1778)
							(mid -0.249642 0.249642)
							(end -0.1778 0.2794)
						)
						(arc
							(start 0.1778 0.2794)
							(mid 0.249642 0.249642)
							(end 0.2794 0.1778)
						)
						(arc
							(start 0.2794 -0.1778)
							(mid 0.249642 -0.249642)
							(end 0.1778 -0.2794)
						)
					)
					(width 0)
					(fill yes)
				)
			)
		)
		(pad "2" smd custom
			(at 0 0.4445 180)
			(size 0.1397 0.1397)
			(layers "F.Cu" "F.Mask" "F.Paste")
			(net "50M_CLK_OUT_R")
			(options
				(clearance outline)
				(anchor circle)
			)
			(primitives
				(gr_poly
					(pts
						(arc
							(start -0.1778 -0.2794)
							(mid -0.249642 -0.249642)
							(end -0.2794 -0.1778)
						)
						(arc
							(start -0.2794 0.1778)
							(mid -0.249642 0.249642)
							(end -0.1778 0.2794)
						)
						(arc
							(start 0.1778 0.2794)
							(mid 0.249642 0.249642)
							(end 0.2794 0.1778)
						)
						(arc
							(start 0.2794 -0.1778)
							(mid 0.249642 -0.249642)
							(end 0.1778 -0.2794)
						)
					)
					(width 0)
					(fill yes)
				)
			)
		)
	)
	(footprint ""
		(layer "F.Cu")
		(at 48.39208 -212.420454 180)
		(property "Reference" "C366"
			(at 0 0 180)
			(layer "F.SilkS")
			(hide yes)
			(effects
				(font
					(size 1.27 1.27)
				)
			)
		)
		(property "Value" "SCD22U10V2KX-1GP"
			(at 1.1811 -2.7051 180)
			(unlocked yes)
			(layer "F.Fab")
			(hide yes)
			(effects
				(font
					(size 1.016 1.016)
					(thickness 0.1524)
				)
			)
		)
		(property "Device Type" "C402H22"
			(at 1.1811 -4.2291 180)
			(unlocked yes)
			(layer "F.Fab")
			(hide yes)
			(effects
				(font
					(size 1.016 1.016)
					(thickness 0.1524)
				)
			)
		)
		(duplicate_pad_numbers_are_jumpers no)
		(fp_rect
			(start -0.4318 0.9525)
			(end 0.4318 -0.9525)
			(stroke
				(width 0)
				(type default)
			)
			(fill no)
			(layer "F.CrtYd")
		)
		(fp_rect
			(start -0.4318 0.9525)
			(end 0.4318 -0.9525)
			(stroke
				(width 0)
				(type default)
			)
			(fill no)
			(layer "F.Fab")
		)
		(pad "1" smd custom
			(at 0 -0.4445 180)
			(size 0.1524 0.1524)
			(layers "F.Cu" "F.Mask" "F.Paste")
			(net "PCIE_TX_CAP_P75")
			(options
				(clearance outline)
				(anchor circle)
			)
			(primitives
				(gr_poly
					(pts
						(arc
							(start 0.3048 -0.2032)
							(mid 0.275042 -0.275042)
							(end 0.2032 -0.3048)
						)
						(arc
							(start -0.2032 -0.3048)
							(mid -0.275042 -0.275042)
							(end -0.3048 -0.2032)
						)
						(arc
							(start -0.3048 0.2032)
							(mid -0.275042 0.275042)
							(end -0.2032 0.3048)
						)
						(arc
							(start 0.2032 0.3048)
							(mid 0.275042 0.275042)
							(end 0.3048 0.2032)
						)
					)
					(width 0)
					(fill yes)
				)
			)
		)
		(pad "2" smd custom
			(at 0 0.4445 180)
			(size 0.1524 0.1524)
			(layers "F.Cu" "F.Mask" "F.Paste")
			(net "PCIE_TX_P75")
			(options
				(clearance outline)
				(anchor circle)
			)
			(primitives
				(gr_poly
					(pts
						(arc
							(start 0.3048 -0.2032)
							(mid 0.275042 -0.275042)
							(end 0.2032 -0.3048)
						)
						(arc
							(start -0.2032 -0.3048)
							(mid -0.275042 -0.275042)
							(end -0.3048 -0.2032)
						)
						(arc
							(start -0.3048 0.2032)
							(mid -0.275042 0.275042)
							(end -0.2032 0.3048)
						)
						(arc
							(start 0.2032 0.3048)
							(mid 0.275042 0.275042)
							(end 0.3048 0.2032)
						)
					)
					(width 0)
					(fill yes)
				)
			)
		)
	)
	(footprint ""
		(layer "F.Cu")
		(at 194.5386 -6.6548 90)
		(property "Reference" "R944"
			(at 0 0 90)
			(layer "F.SilkS")
			(hide yes)
			(effects
				(font
					(size 1.27 1.27)
				)
			)
		)
		(property "Value" "100KR2F-L1-GP"
			(at 0.064008 -3.993896 90)
			(unlocked yes)
			(layer "F.Fab")
			(hide yes)
			(effects
				(font
					(size 1.016 1.016)
					(thickness 0.1524)
				)
			)
		)
		(property "Device Type" "R402H16"
			(at 0.064008 -5.517896 90)
			(unlocked yes)
			(layer "F.Fab")
			(hide yes)
			(effects
				(font
					(size 1.016 1.016)
					(thickness 0.1524)
				)
			)
		)
		(duplicate_pad_numbers_are_jumpers no)
		(fp_line
			(start 0.508 -0.9398)
			(end -0.508 -0.9398)
			(stroke
				(width 0.1524)
				(type default)
			)
			(layer "F.SilkS")
		)
		(fp_line
			(start -0.508 -0.9398)
			(end -0.508 0.9398)
			(stroke
				(width 0.1524)
				(type default)
			)
			(layer "F.SilkS")
		)
		(fp_rect
			(start -0.508 0.9398)
			(end 0.508 -0.9398)
			(stroke
				(width 0)
				(type default)
			)
			(fill no)
			(layer "F.CrtYd")
		)
		(fp_rect
			(start -0.508 0.9398)
			(end 0.508 -0.9398)
			(stroke
				(width 0)
				(type default)
			)
			(fill no)
			(layer "F.Fab")
		)
		(pad "1" smd custom
			(at 0 -0.4445 90)
			(size 0.1397 0.1397)
			(layers "F.Cu" "F.Mask" "F.Paste")
			(net "WP_ENABLE")
			(options
				(clearance outline)
				(anchor circle)
			)
			(primitives
				(gr_poly
					(pts
						(arc
							(start -0.1778 -0.2794)
							(mid -0.249642 -0.249642)
							(end -0.2794 -0.1778)
						)
						(arc
							(start -0.2794 0.1778)
							(mid -0.249642 0.249642)
							(end -0.1778 0.2794)
						)
						(arc
							(start 0.1778 0.2794)
							(mid 0.249642 0.249642)
							(end 0.2794 0.1778)
						)
						(arc
							(start 0.2794 -0.1778)
							(mid 0.249642 -0.249642)
							(end 0.1778 -0.2794)
						)
					)
					(width 0)
					(fill yes)
				)
			)
		)
		(pad "2" smd custom
			(at 0 0.4445 90)
			(size 0.1397 0.1397)
			(layers "F.Cu" "F.Mask" "F.Paste")
			(net "GND")
			(options
				(clearance outline)
				(anchor circle)
			)
			(primitives
				(gr_poly
					(pts
						(arc
							(start -0.1778 -0.2794)
							(mid -0.249642 -0.249642)
							(end -0.2794 -0.1778)
						)
						(arc
							(start -0.2794 0.1778)
							(mid -0.249642 0.249642)
							(end -0.1778 0.2794)
						)
						(arc
							(start 0.1778 0.2794)
							(mid 0.249642 0.249642)
							(end 0.2794 0.1778)
						)
						(arc
							(start 0.2794 -0.1778)
							(mid 0.249642 -0.249642)
							(end 0.1778 -0.2794)
						)
					)
					(width 0)
					(fill yes)
				)
			)
		)
	)
	(footprint ""
		(layer "F.Cu")
		(at 133.7818 -210.7438 -90)
		(property "Reference" "C4144"
			(at 0 0 270)
			(layer "F.SilkS")
			(hide yes)
			(effects
				(font
					(size 1.27 1.27)
				)
			)
		)
		(property "Value" "SCD1U25V3KX-GP"
			(at 0 -2.8194 270)
			(unlocked yes)
			(layer "F.Fab")
			(hide yes)
			(effects
				(font
					(size 1.016 1.016)
					(thickness 0.1524)
				)
			)
		)
		(property "Device Type" "C603H36"
			(at 0 -4.3434 270)
			(unlocked yes)
			(layer "F.Fab")
			(hide yes)
			(effects
				(font
					(size 1.016 1.016)
					(thickness 0.1524)
				)
			)
		)
		(duplicate_pad_numbers_are_jumpers no)
		(fp_line
			(start 0.508 0)
			(end -0.508 0)
			(stroke
				(width 0.2032)
				(type default)
			)
			(layer "F.SilkS")
		)
		(fp_rect
			(start -0.5842 1.3335)
			(end 0.5842 -1.3335)
			(stroke
				(width 0)
				(type default)
			)
			(fill no)
			(layer "F.CrtYd")
		)
		(fp_rect
			(start -0.5842 1.3335)
			(end 0.5842 -1.3335)
			(stroke
				(width 0)
				(type default)
			)
			(fill no)
			(layer "F.Fab")
		)
		(pad "1" smd custom
			(at 0 -0.762 270)
			(size 0.2159 0.2159)
			(layers "F.Cu" "F.Mask" "F.Paste")
			(net "GND")
			(options
				(clearance outline)
				(anchor circle)
			)
			(primitives
				(gr_poly
					(pts
						(arc
							(start -0.3302 -0.4318)
							(mid -0.402042 -0.402042)
							(end -0.4318 -0.3302)
						)
						(arc
							(start -0.4318 0.3302)
							(mid -0.402042 0.402042)
							(end -0.3302 0.4318)
						)
						(arc
							(start 0.3302 0.4318)
							(mid 0.402042 0.402042)
							(end 0.4318 0.3302)
						)
						(arc
							(start 0.4318 -0.3302)
							(mid 0.402042 -0.402042)
							(end 0.3302 -0.4318)
						)
					)
					(width 0)
					(fill yes)
				)
			)
		)
		(pad "2" smd custom
			(at 0 0.762 270)
			(size 0.2159 0.2159)
			(layers "F.Cu" "F.Mask" "F.Paste")
			(net "SSD_PWREN6_R")
			(options
				(clearance outline)
				(anchor circle)
			)
			(primitives
				(gr_poly
					(pts
						(arc
							(start -0.3302 -0.4318)
							(mid -0.402042 -0.402042)
							(end -0.4318 -0.3302)
						)
						(arc
							(start -0.4318 0.3302)
							(mid -0.402042 0.402042)
							(end -0.3302 0.4318)
						)
						(arc
							(start 0.3302 0.4318)
							(mid 0.402042 0.402042)
							(end 0.4318 0.3302)
						)
						(arc
							(start 0.4318 -0.3302)
							(mid 0.402042 -0.402042)
							(end 0.3302 -0.4318)
						)
					)
					(width 0)
					(fill yes)
				)
			)
		)
	)
)
